(kicad_pcb
	(version 20241229)
	(generator "pcbnew")
	(generator_version "9.0")
	(general
		(thickness 1.552)
		(legacy_teardrops no)
	)
	(paper "A4")
	(title_block
		(date "2023-07-25")
		(rev "1.1.4")
		(comment 9 "footprints 318-322 of 379")
	)
	(layers
		(0 "F.Cu" signal)
		(4 "In1.Cu" signal)
		(6 "In2.Cu" signal)
		(8 "In3.Cu" signal)
		(10 "In4.Cu" signal)
		(12 "In5.Cu" signal)
		(14 "In6.Cu" signal)
		(2 "B.Cu" signal)
		(9 "F.Adhes" user "F.Adhesive")
		(11 "B.Adhes" user "B.Adhesive")
		(13 "F.Paste" user)
		(15 "B.Paste" user)
		(5 "F.SilkS" user "F.Silkscreen")
		(7 "B.SilkS" user "B.Silkscreen")
		(1 "F.Mask" user)
		(3 "B.Mask" user)
		(17 "Dwgs.User" user "User.Drawings")
		(19 "Cmts.User" user "User.Comments")
		(21 "Eco1.User" user "User.Eco1")
		(23 "Eco2.User" user "User.Eco2")
		(25 "Edge.Cuts" user)
		(27 "Margin" user)
		(31 "F.CrtYd" user "F.Courtyard")
		(29 "B.CrtYd" user "B.Courtyard")
		(35 "F.Fab" user)
		(33 "B.Fab" user)
	)
	(footprint "antmicro-footprints:C_0201"
		(layer "B.Cu")
		(at 128.3 95.1 180)
		(descr "Capacitor SMD 0201")
		(tags "capacitor SMD 0201")
		(property "Reference" "C95"
			(at 8.47 12.095736 0)
			(layer "B.SilkS")
			(effects
				(font
					(size 0.65 0.65)
					(thickness 0.15)
				)
				(justify left bottom mirror)
			)
		)
		(property "Value" "C_100n_0201"
			(at 0 -1.4 0)
			(layer "B.Fab")
			(hide yes)
			(effects
				(font
					(size 0.7 0.7)
					(thickness 0.15)
				)
				(justify left bottom mirror)
			)
		)
		(property "Datasheet" "https://www.yageo.com/en/Chart/Download/pdf/CC0201KRX6S5BB104"
			(at 0 0 180)
			(layer "F.Fab")
			(hide yes)
			(effects
				(font
					(size 1.27 1.27)
					(thickness 0.15)
				)
			)
		)
		(property "Description" "SMD Multilayer Ceramic Capacitor, 0.1 µF, 6.3 V, 0201 [0603 Metric], ± 10%, X6S, CC Series"
			(at 0 0 180)
			(layer "F.Fab")
			(hide yes)
			(effects
				(font
					(size 1.27 1.27)
					(thickness 0.15)
				)
			)
		)
		(property "Author" "Antmicro"
			(at 256.6 190.2 0)
			(layer "B.Fab")
			(hide yes)
			(effects
				(font
					(size 1 1)
					(thickness 0.15)
				)
				(justify mirror)
			)
		)
		(property "Dielectric" ""
			(at 256.6 190.2 0)
			(layer "B.Fab")
			(hide yes)
			(effects
				(font
					(size 1 1)
					(thickness 0.15)
				)
				(justify mirror)
			)
		)
		(property "License" "Apache-2.0"
			(at 256.6 190.2 0)
			(layer "B.Fab")
			(hide yes)
			(effects
				(font
					(size 1 1)
					(thickness 0.15)
				)
				(justify mirror)
			)
		)
		(property "MPN" "CC0201KRX6S5BB104"
			(at 256.6 190.2 0)
			(layer "B.Fab")
			(hide yes)
			(effects
				(font
					(size 1 1)
					(thickness 0.15)
				)
				(justify mirror)
			)
		)
		(property "Manufacturer" "YAGEO"
			(at 256.6 190.2 0)
			(layer "B.Fab")
			(hide yes)
			(effects
				(font
					(size 1 1)
					(thickness 0.15)
				)
				(justify mirror)
			)
		)
		(property "Val" "100n"
			(at 256.6 190.2 0)
			(layer "B.Fab")
			(hide yes)
			(effects
				(font
					(size 1 1)
					(thickness 0.15)
				)
				(justify mirror)
			)
		)
		(property "Voltage" ""
			(at 256.6 190.2 0)
			(layer "B.Fab")
			(hide yes)
			(effects
				(font
					(size 1 1)
					(thickness 0.15)
				)
				(justify mirror)
			)
		)
		(property "Public" "False"
			(at 0 0 180)
			(unlocked yes)
			(layer "B.Fab")
			(hide yes)
			(effects
				(font
					(size 1 1)
					(thickness 0.15)
				)
				(justify mirror)
			)
		)
		(sheetname "/FPGA Power/")
		(sheetfile "FPGA_Power.kicad_sch")
		(attr smd)
		(fp_rect
			(start -0.7 0.35)
			(end 0.7 -0.35)
			(stroke
				(width 0.05)
				(type default)
			)
			(fill no)
			(layer "B.CrtYd")
		)
		(fp_rect
			(start 0.3 -0.15)
			(end -0.301 0.149)
			(stroke
				(width 0.15)
				(type solid)
			)
			(fill no)
			(layer "B.Fab")
		)
		(fp_text user "${REFERENCE}"
			(at -0.72 -3.4 0)
			(layer "B.Fab")
			(effects
				(font
					(size 0.7 0.7)
					(thickness 0.15)
				)
				(justify left bottom mirror)
			)
		)
		(fp_text user "Author: Antmicro"
			(at -0.72 -5.4 0)
			(layer "B.Fab")
			(effects
				(font
					(size 0.7 0.7)
					(thickness 0.15)
				)
				(justify left bottom mirror)
			)
		)
		(fp_text user "License: Apache-2.0"
			(at -0.72 -4.4 0)
			(layer "B.Fab")
			(effects
				(font
					(size 0.7 0.7)
					(thickness 0.15)
				)
				(justify left bottom mirror)
			)
		)
		(pad "" smd roundrect
			(at -0.349 0.002 180)
			(size 0.318 0.36)
			(layers "B.Paste")
			(roundrect_rratio 0.25)
		)
		(pad "" smd roundrect
			(at 0.341 0.002 180)
			(size 0.318 0.36)
			(layers "B.Paste")
			(roundrect_rratio 0.25)
		)
		(pad "1" smd roundrect
			(at -0.321 0.002 180)
			(size 0.46 0.4)
			(layers "B.Cu" "B.Mask")
			(roundrect_rratio 0.25)
			(net 1 "GND")
			(pintype "passive")
		)
		(pad "2" smd roundrect
			(at 0.32 0.002 180)
			(size 0.46 0.4)
			(layers "B.Cu" "B.Mask")
			(roundrect_rratio 0.25)
			(net 11 "/FPGA Power/VCC_DPHY")
			(pintype "passive")
		)
	)
	(footprint "antmicro-footprints:C_0402_1005Metric"
		(layer "B.Cu")
		(at 127.95 67.72 90)
		(descr "Capacitor SMD 0402")
		(tags "capacitor SMD 0402")
		(property "Reference" "C41"
			(at -1.02 1.38 90)
			(layer "B.SilkS")
			(effects
				(font
					(size 0.65 0.65)
					(thickness 0.15)
				)
				(justify right bottom mirror)
			)
		)
		(property "Value" "C_100n_0402"
			(at 0 -1.4 90)
			(layer "B.Fab")
			(hide yes)
			(effects
				(font
					(size 0.7 0.7)
					(thickness 0.15)
				)
				(justify right bottom mirror)
			)
		)
		(property "Datasheet" "https://www.murata.com/products/productdetail?partno=GRM155R61H104KE14%23"
			(at 0 0 90)
			(layer "F.Fab")
			(hide yes)
			(effects
				(font
					(size 1.27 1.27)
					(thickness 0.15)
				)
			)
		)
		(property "Description" "SMD Multilayer Ceramic Capacitor, 0.1 µF, 50 V, 0402 [1005 Metric], ± 10%, X5R, GRM Series"
			(at 0 0 90)
			(layer "F.Fab")
			(hide yes)
			(effects
				(font
					(size 1.27 1.27)
					(thickness 0.15)
				)
			)
		)
		(property "Author" "Antmicro"
			(at 195.67 -60.23 0)
			(layer "B.Fab")
			(hide yes)
			(effects
				(font
					(size 1 1)
					(thickness 0.15)
				)
				(justify mirror)
			)
		)
		(property "Dielectric" "X5R"
			(at 195.67 -60.23 0)
			(layer "B.Fab")
			(hide yes)
			(effects
				(font
					(size 1 1)
					(thickness 0.15)
				)
				(justify mirror)
			)
		)
		(property "License" "Apache-2.0"
			(at 195.67 -60.23 0)
			(layer "B.Fab")
			(hide yes)
			(effects
				(font
					(size 1 1)
					(thickness 0.15)
				)
				(justify mirror)
			)
		)
		(property "MPN" "GRM155R61H104KE14D"
			(at 195.67 -60.23 0)
			(layer "B.Fab")
			(hide yes)
			(effects
				(font
					(size 1 1)
					(thickness 0.15)
				)
				(justify mirror)
			)
		)
		(property "Manufacturer" "Murata"
			(at 195.67 -60.23 0)
			(layer "B.Fab")
			(hide yes)
			(effects
				(font
					(size 1 1)
					(thickness 0.15)
				)
				(justify mirror)
			)
		)
		(property "Val" "100n"
			(at 195.67 -60.23 0)
			(layer "B.Fab")
			(hide yes)
			(effects
				(font
					(size 1 1)
					(thickness 0.15)
				)
				(justify mirror)
			)
		)
		(property "Voltage" "50V"
			(at 195.67 -60.23 0)
			(layer "B.Fab")
			(hide yes)
			(effects
				(font
					(size 1 1)
					(thickness 0.15)
				)
				(justify mirror)
			)
		)
		(sheetname "/DDR3/")
		(sheetfile "ddr3.kicad_sch")
		(attr smd)
		(fp_rect
			(start -0.925 0.47)
			(end 0.925 -0.47)
			(stroke
				(width 0.05)
				(type default)
			)
			(fill no)
			(layer "B.CrtYd")
		)
		(fp_line
			(start 0.504 -0.248)
			(end -0.494 -0.248)
			(stroke
				(width 0.15)
				(type solid)
			)
			(layer "B.Fab")
		)
		(fp_line
			(start -0.494 -0.248)
			(end -0.494 0.25)
			(stroke
				(width 0.15)
				(type solid)
			)
			(layer "B.Fab")
		)
		(fp_line
			(start 0.504 0.25)
			(end 0.504 -0.248)
			(stroke
				(width 0.15)
				(type solid)
			)
			(layer "B.Fab")
		)
		(fp_line
			(start -0.494 0.25)
			(end 0.504 0.25)
			(stroke
				(width 0.15)
				(type solid)
			)
			(layer "B.Fab")
		)
		(fp_text user "License: Apache-2.0"
			(at -0.939 -5.799 270)
			(layer "B.Fab")
			(effects
				(font
					(size 0.7 0.7)
					(thickness 0.15)
				)
				(justify left bottom mirror)
			)
		)
		(fp_text user "Author: Antmicro"
			(at -0.939 -3.399 270)
			(layer "B.Fab")
			(effects
				(font
					(size 0.7 0.7)
					(thickness 0.15)
				)
				(justify left bottom mirror)
			)
		)
		(fp_text user "${REFERENCE}"
			(at -0.939 -4.599 270)
			(layer "B.Fab")
			(effects
				(font
					(size 0.7 0.7)
					(thickness 0.15)
				)
				(justify left bottom mirror)
			)
		)
		(pad "1" smd roundrect
			(at -0.48 0 90)
			(size 0.59 0.64)
			(layers "B.Cu" "B.Mask" "B.Paste")
			(roundrect_rratio 0.25)
			(net 1 "GND")
			(pintype "passive")
		)
		(pad "2" smd roundrect
			(at 0.48 0 90)
			(size 0.59 0.64)
			(layers "B.Cu" "B.Mask" "B.Paste")
			(roundrect_rratio 0.25)
			(net 248 "+1V5")
			(pintype "passive")
		)
	)
	(footprint "antmicro-footprints:R_0402_1005Metric"
		(layer "B.Cu")
		(at 145.2 81.5 -90)
		(descr "Resistor SMD 0402")
		(tags "resistor SMD 0402")
		(property "Reference" "R134"
			(at -3.66 -0.33 90)
			(layer "B.SilkS")
			(effects
				(font
					(size 0.65 0.65)
					(thickness 0.15)
				)
				(justify left bottom mirror)
			)
		)
		(property "Value" "R_27R_0402"
			(at 0 -1.4 90)
			(layer "B.Fab")
			(hide yes)
			(effects
				(font
					(size 0.7 0.7)
					(thickness 0.15)
				)
				(justify left bottom mirror)
			)
		)
		(property "Datasheet" "https://www.bourns.com/docs/product-datasheets/cr.pdf"
			(at 0 0 270)
			(layer "F.Fab")
			(hide yes)
			(effects
				(font
					(size 1.27 1.27)
					(thickness 0.15)
				)
			)
		)
		(property "Description" "SMD Chip Resistor, 27 ohm, ± 1%, 63 mW, 0402 [1005 Metric], Thick Film, General Purpose"
			(at 0 0 270)
			(layer "F.Fab")
			(hide yes)
			(effects
				(font
					(size 1.27 1.27)
					(thickness 0.15)
				)
			)
		)
		(property "Author" "Antmicro"
			(at 63.7 226.7 0)
			(layer "B.Fab")
			(hide yes)
			(effects
				(font
					(size 1 1)
					(thickness 0.15)
				)
				(justify mirror)
			)
		)
		(property "License" "Apache-2.0"
			(at 63.7 226.7 0)
			(layer "B.Fab")
			(hide yes)
			(effects
				(font
					(size 1 1)
					(thickness 0.15)
				)
				(justify mirror)
			)
		)
		(property "MPN" "CR0402-FX-27R0GLF"
			(at 63.7 226.7 0)
			(layer "B.Fab")
			(hide yes)
			(effects
				(font
					(size 1 1)
					(thickness 0.15)
				)
				(justify mirror)
			)
		)
		(property "Manufacturer" "Bourns"
			(at 63.7 226.7 0)
			(layer "B.Fab")
			(hide yes)
			(effects
				(font
					(size 1 1)
					(thickness 0.15)
				)
				(justify mirror)
			)
		)
		(property "Tolerance" "1%"
			(at 63.7 226.7 0)
			(layer "B.Fab")
			(hide yes)
			(effects
				(font
					(size 1 1)
					(thickness 0.15)
				)
				(justify mirror)
			)
		)
		(property "Val" "27R"
			(at 63.7 226.7 0)
			(layer "B.Fab")
			(hide yes)
			(effects
				(font
					(size 1 1)
					(thickness 0.15)
				)
				(justify mirror)
			)
		)
		(sheetname "/Peripherals/")
		(sheetfile "peripherals.kicad_sch")
		(attr smd)
		(fp_rect
			(start -0.925 0.47)
			(end 0.925 -0.47)
			(stroke
				(width 0.05)
				(type default)
			)
			(fill no)
			(layer "B.CrtYd")
		)
		(fp_rect
			(start -0.5 0.25)
			(end 0.5 -0.25)
			(stroke
				(width 0.15)
				(type solid)
			)
			(fill no)
			(layer "B.Fab")
		)
		(fp_text user "${REFERENCE}"
			(at -0.95 -3.168 90)
			(layer "B.Fab")
			(effects
				(font
					(size 0.7 0.7)
					(thickness 0.15)
				)
				(justify left bottom mirror)
			)
		)
		(fp_text user "License: Apache-2.0"
			(at -0.95 -5.169 90)
			(layer "B.Fab")
			(effects
				(font
					(size 0.7 0.7)
					(thickness 0.15)
				)
				(justify left bottom mirror)
			)
		)
		(fp_text user "Author: Antmicro"
			(at -0.95 -4.169 90)
			(layer "B.Fab")
			(effects
				(font
					(size 0.7 0.7)
					(thickness 0.15)
				)
				(justify left bottom mirror)
			)
		)
		(pad "1" smd roundrect
			(at -0.48 0 270)
			(size 0.59 0.64)
			(layers "B.Cu" "B.Mask" "B.Paste")
			(roundrect_rratio 0.25)
			(net 359 "/Peripherals/USB_DP")
			(pintype "passive")
		)
		(pad "2" smd roundrect
			(at 0.48 0 270)
			(size 0.59 0.64)
			(layers "B.Cu" "B.Mask" "B.Paste")
			(roundrect_rratio 0.25)
			(net 362 "/Peripherals/USB_D2P")
			(pintype "passive")
		)
	)
	(footprint "antmicro-footprints:C_0201"
		(layer "B.Cu")
		(at 122.3 89.9 -90)
		(descr "Capacitor SMD 0201")
		(tags "capacitor SMD 0201")
		(property "Reference" "C115"
			(at -13.895736 9.07 90)
			(layer "B.SilkS")
			(effects
				(font
					(size 0.65 0.65)
					(thickness 0.15)
				)
				(justify left bottom mirror)
			)
		)
		(property "Value" "C_100n_0201"
			(at 0 -1.4 90)
			(layer "B.Fab")
			(hide yes)
			(effects
				(font
					(size 0.7 0.7)
					(thickness 0.15)
				)
				(justify left bottom mirror)
			)
		)
		(property "Datasheet" "https://www.yageo.com/en/Chart/Download/pdf/CC0201KRX6S5BB104"
			(at 0 0 270)
			(layer "F.Fab")
			(hide yes)
			(effects
				(font
					(size 1.27 1.27)
					(thickness 0.15)
				)
			)
		)
		(property "Description" "SMD Multilayer Ceramic Capacitor, 0.1 µF, 6.3 V, 0201 [0603 Metric], ± 10%, X6S, CC Series"
			(at 0 0 270)
			(layer "F.Fab")
			(hide yes)
			(effects
				(font
					(size 1.27 1.27)
					(thickness 0.15)
				)
			)
		)
		(property "Author" "Antmicro"
			(at 32.4 212.2 0)
			(layer "B.Fab")
			(hide yes)
			(effects
				(font
					(size 1 1)
					(thickness 0.15)
				)
				(justify mirror)
			)
		)
		(property "Dielectric" ""
			(at 32.4 212.2 0)
			(layer "B.Fab")
			(hide yes)
			(effects
				(font
					(size 1 1)
					(thickness 0.15)
				)
				(justify mirror)
			)
		)
		(property "License" "Apache-2.0"
			(at 32.4 212.2 0)
			(layer "B.Fab")
			(hide yes)
			(effects
				(font
					(size 1 1)
					(thickness 0.15)
				)
				(justify mirror)
			)
		)
		(property "MPN" "CC0201KRX6S5BB104"
			(at 32.4 212.2 0)
			(layer "B.Fab")
			(hide yes)
			(effects
				(font
					(size 1 1)
					(thickness 0.15)
				)
				(justify mirror)
			)
		)
		(property "Manufacturer" "YAGEO"
			(at 32.4 212.2 0)
			(layer "B.Fab")
			(hide yes)
			(effects
				(font
					(size 1 1)
					(thickness 0.15)
				)
				(justify mirror)
			)
		)
		(property "Val" "100n"
			(at 32.4 212.2 0)
			(layer "B.Fab")
			(hide yes)
			(effects
				(font
					(size 1 1)
					(thickness 0.15)
				)
				(justify mirror)
			)
		)
		(property "Voltage" ""
			(at 32.4 212.2 0)
			(layer "B.Fab")
			(hide yes)
			(effects
				(font
					(size 1 1)
					(thickness 0.15)
				)
				(justify mirror)
			)
		)
		(property "Public" "False"
			(at 0 0 270)
			(unlocked yes)
			(layer "B.Fab")
			(hide yes)
			(effects
				(font
					(size 1 1)
					(thickness 0.15)
				)
				(justify mirror)
			)
		)
		(sheetname "/SDI/")
		(sheetfile "sdi.kicad_sch")
		(attr smd)
		(fp_rect
			(start -0.7 0.35)
			(end 0.7 -0.35)
			(stroke
				(width 0.05)
				(type default)
			)
			(fill no)
			(layer "B.CrtYd")
		)
		(fp_rect
			(start 0.3 -0.15)
			(end -0.301 0.149)
			(stroke
				(width 0.15)
				(type solid)
			)
			(fill no)
			(layer "B.Fab")
		)
		(fp_text user "Author: Antmicro"
			(at -0.72 -5.4 90)
			(layer "B.Fab")
			(effects
				(font
					(size 0.7 0.7)
					(thickness 0.15)
				)
				(justify left bottom mirror)
			)
		)
		(fp_text user "${REFERENCE}"
			(at -0.72 -3.4 90)
			(layer "B.Fab")
			(effects
				(font
					(size 0.7 0.7)
					(thickness 0.15)
				)
				(justify left bottom mirror)
			)
		)
		(fp_text user "License: Apache-2.0"
			(at -0.72 -4.4 90)
			(layer "B.Fab")
			(effects
				(font
					(size 0.7 0.7)
					(thickness 0.15)
				)
				(justify left bottom mirror)
			)
		)
		(pad "" smd roundrect
			(at -0.349 0.002 270)
			(size 0.318 0.36)
			(layers "B.Paste")
			(roundrect_rratio 0.25)
		)
		(pad "" smd roundrect
			(at 0.341 0.002 270)
			(size 0.318 0.36)
			(layers "B.Paste")
			(roundrect_rratio 0.25)
		)
		(pad "1" smd roundrect
			(at -0.321 0.002 270)
			(size 0.46 0.4)
			(layers "B.Cu" "B.Mask")
			(roundrect_rratio 0.25)
			(net 1 "GND")
			(pintype "passive")
		)
		(pad "2" smd roundrect
			(at 0.32 0.002 270)
			(size 0.46 0.4)
			(layers "B.Cu" "B.Mask")
			(roundrect_rratio 0.25)
			(net 2 "+3V3")
			(pintype "passive")
		)
	)
	(footprint "antmicro-footprints:R_0402_1005Metric"
		(layer "B.Cu")
		(at 146.2 81.5 -90)
		(descr "Resistor SMD 0402")
		(tags "resistor SMD 0402")
		(property "Reference" "R133"
			(at -3.66 -0.33 90)
			(layer "B.SilkS")
			(effects
				(font
					(size 0.65 0.65)
					(thickness 0.15)
				)
				(justify left bottom mirror)
			)
		)
		(property "Value" "R_27R_0402"
			(at 0 -1.4 90)
			(layer "B.Fab")
			(hide yes)
			(effects
				(font
					(size 0.7 0.7)
					(thickness 0.15)
				)
				(justify left bottom mirror)
			)
		)
		(property "Datasheet" "https://www.bourns.com/docs/product-datasheets/cr.pdf"
			(at 0 0 270)
			(layer "F.Fab")
			(hide yes)
			(effects
				(font
					(size 1.27 1.27)
					(thickness 0.15)
				)
			)
		)
		(property "Description" "SMD Chip Resistor, 27 ohm, ± 1%, 63 mW, 0402 [1005 Metric], Thick Film, General Purpose"
			(at 0 0 270)
			(layer "F.Fab")
			(hide yes)
			(effects
				(font
					(size 1.27 1.27)
					(thickness 0.15)
				)
			)
		)
		(property "Author" "Antmicro"
			(at 64.7 227.7 0)
			(layer "B.Fab")
			(hide yes)
			(effects
				(font
					(size 1 1)
					(thickness 0.15)
				)
				(justify mirror)
			)
		)
		(property "License" "Apache-2.0"
			(at 64.7 227.7 0)
			(layer "B.Fab")
			(hide yes)
			(effects
				(font
					(size 1 1)
					(thickness 0.15)
				)
				(justify mirror)
			)
		)
		(property "MPN" "CR0402-FX-27R0GLF"
			(at 64.7 227.7 0)
			(layer "B.Fab")
			(hide yes)
			(effects
				(font
					(size 1 1)
					(thickness 0.15)
				)
				(justify mirror)
			)
		)
		(property "Manufacturer" "Bourns"
			(at 64.7 227.7 0)
			(layer "B.Fab")
			(hide yes)
			(effects
				(font
					(size 1 1)
					(thickness 0.15)
				)
				(justify mirror)
			)
		)
		(property "Tolerance" "1%"
			(at 64.7 227.7 0)
			(layer "B.Fab")
			(hide yes)
			(effects
				(font
					(size 1 1)
					(thickness 0.15)
				)
				(justify mirror)
			)
		)
		(property "Val" "27R"
			(at 64.7 227.7 0)
			(layer "B.Fab")
			(hide yes)
			(effects
				(font
					(size 1 1)
					(thickness 0.15)
				)
				(justify mirror)
			)
		)
		(sheetname "/Peripherals/")
		(sheetfile "peripherals.kicad_sch")
		(attr smd)
		(fp_rect
			(start -0.925 0.47)
			(end 0.925 -0.47)
			(stroke
				(width 0.05)
				(type default)
			)
			(fill no)
			(layer "B.CrtYd")
		)
		(fp_rect
			(start -0.5 0.25)
			(end 0.5 -0.25)
			(stroke
				(width 0.15)
				(type solid)
			)
			(fill no)
			(layer "B.Fab")
		)
		(fp_text user "License: Apache-2.0"
			(at -0.95 -5.169 90)
			(layer "B.Fab")
			(effects
				(font
					(size 0.7 0.7)
					(thickness 0.15)
				)
				(justify left bottom mirror)
			)
		)
		(fp_text user "${REFERENCE}"
			(at -0.95 -3.168 90)
			(layer "B.Fab")
			(effects
				(font
					(size 0.7 0.7)
					(thickness 0.15)
				)
				(justify left bottom mirror)
			)
		)
		(fp_text user "Author: Antmicro"
			(at -0.95 -4.169 90)
			(layer "B.Fab")
			(effects
				(font
					(size 0.7 0.7)
					(thickness 0.15)
				)
				(justify left bottom mirror)
			)
		)
		(pad "1" smd roundrect
			(at -0.48 0 270)
			(size 0.59 0.64)
			(layers "B.Cu" "B.Mask" "B.Paste")
			(roundrect_rratio 0.25)
			(net 360 "/Peripherals/USB_DN")
			(pintype "passive")
		)
		(pad "2" smd roundrect
			(at 0.48 0 270)
			(size 0.59 0.64)
			(layers "B.Cu" "B.Mask" "B.Paste")
			(roundrect_rratio 0.25)
			(net 361 "/Peripherals/USB_D2N")
			(pintype "passive")
		)
	)
)
